(kicad_pcb
	(version 20241229)
	(generator "pcbnew")
	(generator_version "9.0")
	(general
		(thickness 1.62)
		(legacy_teardrops no)
	)
	(paper "A3")
	(title_block
		(title "COM Express 7 Baseboard")
		(date "2025-02-04")
		(rev "1.1.2")
		(company "Antmicro Ltd")
		(comment 1 "www.antmicro.com")
		(comment 9 "footprints 581-585 of 802")
	)
	(layers
		(0 "F.Cu" signal)
		(4 "In1.Cu" signal)
		(6 "In2.Cu" signal)
		(8 "In3.Cu" signal)
		(10 "In4.Cu" signal)
		(12 "In5.Cu" signal)
		(14 "In6.Cu" signal)
		(2 "B.Cu" signal)
		(9 "F.Adhes" user "F.Adhesive")
		(11 "B.Adhes" user "B.Adhesive")
		(13 "F.Paste" user)
		(15 "B.Paste" user)
		(5 "F.SilkS" user "F.Silkscreen")
		(7 "B.SilkS" user "B.Silkscreen")
		(1 "F.Mask" user)
		(3 "B.Mask" user)
		(17 "Dwgs.User" user "User.Drawings")
		(19 "Cmts.User" user "User.Comments")
		(21 "Eco1.User" user "User.Eco1")
		(23 "Eco2.User" user "User.Eco2")
		(25 "Edge.Cuts" user)
		(27 "Margin" user)
		(31 "F.CrtYd" user "F.Courtyard")
		(29 "B.CrtYd" user "B.Courtyard")
		(35 "F.Fab" user)
		(33 "B.Fab" user)
	)
	(footprint "antmicro-footprints:C_0402_1005Metric"
		(layer "B.Cu")
		(at 154.95 133.86 180)
		(descr "Capacitor SMD 0402")
		(tags "capacitor SMD 0402")
		(property "Reference" "C158"
			(at -3.7 -0.45 180)
			(layer "B.SilkS")
			(effects
				(font
					(size 0.7 0.7)
					(thickness 0.15)
				)
				(justify left bottom mirror)
			)
		)
		(property "Value" "C_100n_0402"
			(at -1.022927 -2.155213 0)
			(layer "B.Fab")
			(effects
				(font
					(size 0.7 0.7)
					(thickness 0.15)
				)
				(justify left bottom mirror)
			)
		)
		(property "Datasheet" "https://www.murata.com/products/productdetail?partno=GRM155R61H104KE14%23"
			(at 0 0 180)
			(layer "F.Fab")
			(hide yes)
			(effects
				(font
					(size 1.27 1.27)
					(thickness 0.15)
				)
			)
		)
		(property "Author" "Antmicro"
			(at 309.9 267.72 0)
			(layer "B.Fab")
			(hide yes)
			(effects
				(font
					(size 1 1)
					(thickness 0.15)
				)
				(justify mirror)
			)
		)
		(property "Dielectric" "X5R"
			(at 309.9 267.72 0)
			(layer "B.Fab")
			(hide yes)
			(effects
				(font
					(size 1 1)
					(thickness 0.15)
				)
				(justify mirror)
			)
		)
		(property "License" "Apache-2.0"
			(at 309.9 267.72 0)
			(layer "B.Fab")
			(hide yes)
			(effects
				(font
					(size 1 1)
					(thickness 0.15)
				)
				(justify mirror)
			)
		)
		(property "MPN" "GRM155R61H104KE14D"
			(at 309.9 267.72 0)
			(layer "B.Fab")
			(hide yes)
			(effects
				(font
					(size 1 1)
					(thickness 0.15)
				)
				(justify mirror)
			)
		)
		(property "Manufacturer" "Murata"
			(at 309.9 267.72 0)
			(layer "B.Fab")
			(hide yes)
			(effects
				(font
					(size 1 1)
					(thickness 0.15)
				)
				(justify mirror)
			)
		)
		(property "Public" "False"
			(at 309.9 267.72 0)
			(layer "B.Fab")
			(hide yes)
			(effects
				(font
					(size 1 1)
					(thickness 0.15)
				)
				(justify mirror)
			)
		)
		(property "Val" "100n"
			(at 309.9 267.72 0)
			(layer "B.Fab")
			(hide yes)
			(effects
				(font
					(size 1 1)
					(thickness 0.15)
				)
				(justify mirror)
			)
		)
		(property "Voltage" "50V"
			(at 309.9 267.72 0)
			(layer "B.Fab")
			(hide yes)
			(effects
				(font
					(size 1 1)
					(thickness 0.15)
				)
				(justify mirror)
			)
		)
		(sheetname "KR to SFI #1")
		(sheetfile "kr_sfi.kicad_sch")
		(attr smd)
		(fp_rect
			(start -0.925 0.47)
			(end 0.925 -0.47)
			(stroke
				(width 0.05)
				(type default)
			)
			(fill no)
			(layer "B.CrtYd")
		)
		(fp_line
			(start 0.504 0.25)
			(end -0.494 0.25)
			(stroke
				(width 0.15)
				(type solid)
			)
			(layer "B.Fab")
		)
		(fp_line
			(start 0.504 -0.248)
			(end 0.504 0.25)
			(stroke
				(width 0.15)
				(type solid)
			)
			(layer "B.Fab")
		)
		(fp_line
			(start -0.494 0.25)
			(end -0.494 -0.248)
			(stroke
				(width 0.15)
				(type solid)
			)
			(layer "B.Fab")
		)
		(fp_line
			(start -0.494 -0.248)
			(end 0.504 -0.248)
			(stroke
				(width 0.15)
				(type solid)
			)
			(layer "B.Fab")
		)
		(pad "1" smd roundrect
			(at -0.48 0 180)
			(size 0.59 0.64)
			(layers "B.Cu" "B.Mask" "B.Paste")
			(roundrect_rratio 0.25)
			(net 1 "GND")
			(pintype "passive")
			(teardrops
				(best_length_ratio 0.2)
				(max_length 1)
				(best_width_ratio 0.9)
				(max_width 2)
				(curved_edges yes)
				(filter_ratio 0.9)
				(enabled yes)
				(allow_two_segments yes)
				(prefer_zone_connections yes)
			)
		)
		(pad "2" smd roundrect
			(at 0.48 0 180)
			(size 0.59 0.64)
			(layers "B.Cu" "B.Mask" "B.Paste")
			(roundrect_rratio 0.25)
			(net 78 "+1V8")
			(pintype "passive")
			(teardrops
				(best_length_ratio 0.2)
				(max_length 1)
				(best_width_ratio 0.9)
				(max_width 2)
				(curved_edges yes)
				(filter_ratio 0.9)
				(enabled yes)
				(allow_two_segments yes)
				(prefer_zone_connections yes)
			)
		)
	)
	(footprint "antmicro-footprints:C_0402_1005Metric"
		(layer "B.Cu")
		(at 132.29 141.36 90)
		(descr "Capacitor SMD 0402")
		(tags "capacitor SMD 0402")
		(property "Reference" "C188"
			(at -3.65 0.11 90)
			(layer "B.SilkS")
			(effects
				(font
					(size 0.7 0.7)
					(thickness 0.15)
				)
				(justify right bottom mirror)
			)
		)
		(property "Value" "C_100n_0402"
			(at -1.022927 -2.155213 90)
			(layer "B.Fab")
			(effects
				(font
					(size 0.7 0.7)
					(thickness 0.15)
				)
				(justify right bottom mirror)
			)
		)
		(property "Datasheet" "https://www.murata.com/products/productdetail?partno=GRM155R61H104KE14%23"
			(at 0 0 90)
			(layer "F.Fab")
			(hide yes)
			(effects
				(font
					(size 1.27 1.27)
					(thickness 0.15)
				)
			)
		)
		(property "Author" "Antmicro"
			(at 273.65 9.07 0)
			(layer "B.Fab")
			(hide yes)
			(effects
				(font
					(size 1 1)
					(thickness 0.15)
				)
				(justify mirror)
			)
		)
		(property "Dielectric" "X5R"
			(at 273.65 9.07 0)
			(layer "B.Fab")
			(hide yes)
			(effects
				(font
					(size 1 1)
					(thickness 0.15)
				)
				(justify mirror)
			)
		)
		(property "License" "Apache-2.0"
			(at 273.65 9.07 0)
			(layer "B.Fab")
			(hide yes)
			(effects
				(font
					(size 1 1)
					(thickness 0.15)
				)
				(justify mirror)
			)
		)
		(property "MPN" "GRM155R61H104KE14D"
			(at 273.65 9.07 0)
			(layer "B.Fab")
			(hide yes)
			(effects
				(font
					(size 1 1)
					(thickness 0.15)
				)
				(justify mirror)
			)
		)
		(property "Manufacturer" "Murata"
			(at 273.65 9.07 0)
			(layer "B.Fab")
			(hide yes)
			(effects
				(font
					(size 1 1)
					(thickness 0.15)
				)
				(justify mirror)
			)
		)
		(property "Public" "False"
			(at 273.65 9.07 0)
			(layer "B.Fab")
			(hide yes)
			(effects
				(font
					(size 1 1)
					(thickness 0.15)
				)
				(justify mirror)
			)
		)
		(property "Val" "100n"
			(at 273.65 9.07 0)
			(layer "B.Fab")
			(hide yes)
			(effects
				(font
					(size 1 1)
					(thickness 0.15)
				)
				(justify mirror)
			)
		)
		(property "Voltage" "50V"
			(at 273.65 9.07 0)
			(layer "B.Fab")
			(hide yes)
			(effects
				(font
					(size 1 1)
					(thickness 0.15)
				)
				(justify mirror)
			)
		)
		(sheetname "KR to SFI #2")
		(sheetfile "kr_sfi.kicad_sch")
		(attr smd)
		(fp_rect
			(start -0.925 0.47)
			(end 0.925 -0.47)
			(stroke
				(width 0.05)
				(type default)
			)
			(fill no)
			(layer "B.CrtYd")
		)
		(fp_line
			(start 0.504 -0.248)
			(end 0.504 0.25)
			(stroke
				(width 0.15)
				(type solid)
			)
			(layer "B.Fab")
		)
		(fp_line
			(start -0.494 -0.248)
			(end 0.504 -0.248)
			(stroke
				(width 0.15)
				(type solid)
			)
			(layer "B.Fab")
		)
		(fp_line
			(start 0.504 0.25)
			(end -0.494 0.25)
			(stroke
				(width 0.15)
				(type solid)
			)
			(layer "B.Fab")
		)
		(fp_line
			(start -0.494 0.25)
			(end -0.494 -0.248)
			(stroke
				(width 0.15)
				(type solid)
			)
			(layer "B.Fab")
		)
		(pad "1" smd roundrect
			(at -0.48 0 90)
			(size 0.59 0.64)
			(layers "B.Cu" "B.Mask" "B.Paste")
			(roundrect_rratio 0.25)
			(net 1 "GND")
			(pintype "passive")
			(teardrops
				(best_length_ratio 0.2)
				(max_length 1)
				(best_width_ratio 0.9)
				(max_width 2)
				(curved_edges yes)
				(filter_ratio 0.9)
				(enabled yes)
				(allow_two_segments yes)
				(prefer_zone_connections yes)
			)
		)
		(pad "2" smd roundrect
			(at 0.48 0 90)
			(size 0.59 0.64)
			(layers "B.Cu" "B.Mask" "B.Paste")
			(roundrect_rratio 0.25)
			(net 74 "+1V0")
			(pintype "passive")
			(teardrops
				(best_length_ratio 0.2)
				(max_length 1)
				(best_width_ratio 0.9)
				(max_width 2)
				(curved_edges yes)
				(filter_ratio 0.9)
				(enabled yes)
				(allow_two_segments yes)
				(prefer_zone_connections yes)
			)
		)
	)
	(footprint "antmicro-footprints:LED_0603_1608Metric_G"
		(layer "B.Cu")
		(at 177.3 88.76)
		(descr "LED SMD 0603 Green")
		(tags "LED SMD 0603 Green")
		(property "Reference" "D13"
			(at -1.05 -0.7 0)
			(layer "B.SilkS")
			(effects
				(font
					(size 0.7 0.7)
					(thickness 0.15)
				)
				(justify right bottom mirror)
			)
		)
		(property "Value" "LED_G_0603_LTST-C190GKT"
			(at -0.001 -1.599 0)
			(layer "B.Fab")
			(effects
				(font
					(size 0.7 0.7)
					(thickness 0.15)
				)
				(justify right bottom mirror)
			)
		)
		(property "Datasheet" "https://media.digikey.com/pdf/Data%20Sheets/Lite-On%20PDFs/LTST-C190GKT.pdf"
			(at 0 0 0)
			(layer "F.Fab")
			(hide yes)
			(effects
				(font
					(size 1.27 1.27)
					(thickness 0.15)
				)
			)
		)
		(property "Author" "Antmicro"
			(at 0 0 0)
			(layer "B.Fab")
			(hide yes)
			(effects
				(font
					(size 1 1)
					(thickness 0.15)
				)
				(justify mirror)
			)
		)
		(property "Color" "Green"
			(at 0 0 0)
			(layer "B.Fab")
			(hide yes)
			(effects
				(font
					(size 1 1)
					(thickness 0.15)
				)
				(justify mirror)
			)
		)
		(property "License" "Apache-2.0"
			(at 0 0 0)
			(layer "B.Fab")
			(hide yes)
			(effects
				(font
					(size 1 1)
					(thickness 0.15)
				)
				(justify mirror)
			)
		)
		(property "MPN" "LTST-C190GKT"
			(at 0 0 0)
			(layer "B.Fab")
			(hide yes)
			(effects
				(font
					(size 1 1)
					(thickness 0.15)
				)
				(justify mirror)
			)
		)
		(property "Manufacturer" "Lite-On"
			(at 0 0 0)
			(layer "B.Fab")
			(hide yes)
			(effects
				(font
					(size 1 1)
					(thickness 0.15)
				)
				(justify mirror)
			)
		)
		(property "Public" "False"
			(at 0 0 0)
			(layer "B.Fab")
			(hide yes)
			(effects
				(font
					(size 1 1)
					(thickness 0.15)
				)
				(justify mirror)
			)
		)
		(sheetname "M.2 key M #1")
		(sheetfile "m2keym_low.kicad_sch")
		(attr smd)
		(fp_line
			(start -1.18 -0.321)
			(end -1.18 0.319)
			(stroke
				(width 0.15)
				(type solid)
			)
			(layer "B.SilkS")
		)
		(fp_line
			(start -0.24 -0.001008)
			(end -0.094672 -0.001008)
			(stroke
				(width 0.1)
				(type solid)
			)
			(layer "B.SilkS")
		)
		(fp_line
			(start -0.22 -0.35)
			(end 0.22 -0.35)
			(stroke
				(width 0.15)
				(type solid)
			)
			(layer "B.SilkS")
		)
		(fp_line
			(start -0.22 0.35)
			(end 0.22 0.35)
			(stroke
				(width 0.15)
				(type solid)
			)
			(layer "B.SilkS")
		)
		(fp_line
			(start -0.094672 -0.001008)
			(end 0.105328 -0.201008)
			(stroke
				(width 0.1)
				(type solid)
			)
			(layer "B.SilkS")
		)
		(fp_line
			(start -0.094672 0.198992)
			(end -0.094672 -0.201008)
			(stroke
				(width 0.1)
				(type solid)
			)
			(layer "B.SilkS")
		)
		(fp_line
			(start 0.105328 0.198992)
			(end -0.094672 -0.001008)
			(stroke
				(width 0.1)
				(type solid)
			)
			(layer "B.SilkS")
		)
		(fp_line
			(start 0.105328 0.198992)
			(end 0.105328 -0.201008)
			(stroke
				(width 0.1)
				(type solid)
			)
			(layer "B.SilkS")
		)
		(fp_line
			(start 0.24 -0.001)
			(end 0.105328 -0.001008)
			(stroke
				(width 0.1)
				(type solid)
			)
			(layer "B.SilkS")
		)
		(fp_rect
			(start 1.25 -0.65)
			(end -1.25 0.65)
			(stroke
				(width 0.05)
				(type solid)
			)
			(fill no)
			(layer "B.CrtYd")
		)
		(fp_line
			(start -0.597 0)
			(end -0.199 0)
			(stroke
				(width 0.15)
				(type solid)
			)
			(layer "B.Fab")
		)
		(fp_line
			(start -0.199 -0.1)
			(end -0.199 -0.2)
			(stroke
				(width 0.15)
				(type solid)
			)
			(layer "B.Fab")
		)
		(fp_line
			(start -0.199 -0.1)
			(end -0.199 0.202)
			(stroke
				(width 0.15)
				(type solid)
			)
			(layer "B.Fab")
		)
		(fp_line
			(start -0.101 0)
			(end 0.201 0.202)
			(stroke
				(width 0.15)
				(type solid)
			)
			(layer "B.Fab")
		)
		(fp_line
			(start 0.201 -0.2)
			(end -0.101 0)
			(stroke
				(width 0.15)
				(type solid)
			)
			(layer "B.Fab")
		)
		(fp_line
			(start 0.201 0)
			(end 0.201 -0.2)
			(stroke
				(width 0.15)
				(type solid)
			)
			(layer "B.Fab")
		)
		(fp_line
			(start 0.201 0)
			(end 0.599 0)
			(stroke
				(width 0.15)
				(type solid)
			)
			(layer "B.Fab")
		)
		(fp_line
			(start 0.201 0.202)
			(end 0.201 0)
			(stroke
				(width 0.15)
				(type solid)
			)
			(layer "B.Fab")
		)
		(fp_rect
			(start 0.848 -0.4)
			(end -0.85 0.402)
			(stroke
				(width 0.15)
				(type solid)
			)
			(fill no)
			(layer "B.Fab")
		)
		(pad "1" smd roundrect
			(at -0.7 0 180)
			(size 0.8 1)
			(layers "B.Cu" "B.Mask" "B.Paste")
			(roundrect_rratio 0.2)
			(net 935 "Net-(D13-C)")
			(pinfunction "C")
			(pintype "passive")
			(teardrops
				(best_length_ratio 0.2)
				(max_length 1)
				(best_width_ratio 0.9)
				(max_width 2)
				(curved_edges yes)
				(filter_ratio 0.9)
				(enabled yes)
				(allow_two_segments yes)
				(prefer_zone_connections yes)
			)
		)
		(pad "2" smd roundrect
			(at 0.7 0 180)
			(size 0.8 1)
			(layers "B.Cu" "B.Mask" "B.Paste")
			(roundrect_rratio 0.2)
			(net 891 "Net-(D13-A)")
			(pinfunction "A")
			(pintype "passive")
			(teardrops
				(best_length_ratio 0.2)
				(max_length 1)
				(best_width_ratio 0.9)
				(max_width 2)
				(curved_edges yes)
				(filter_ratio 0.9)
				(enabled yes)
				(allow_two_segments yes)
				(prefer_zone_connections yes)
			)
		)
	)
	(footprint "antmicro-footprints:R_0402_1005Metric"
		(layer "B.Cu")
		(at 179.890001 88.76)
		(descr "Resistor SMD 0402")
		(tags "resistor SMD 0402")
		(property "Reference" "R123"
			(at -1.390001 -0.5 0)
			(layer "B.SilkS")
			(effects
				(font
					(size 0.7 0.7)
					(thickness 0.15)
				)
				(justify right bottom mirror)
			)
		)
		(property "Value" "R_220R_0402"
			(at -1.011843 -1.772047 0)
			(layer "B.Fab")
			(effects
				(font
					(size 0.7 0.7)
					(thickness 0.15)
				)
				(justify right bottom mirror)
			)
		)
		(property "Datasheet" "https://www.bourns.com/docs/product-datasheets/cr.pdf"
			(at 0 0 0)
			(layer "F.Fab")
			(hide yes)
			(effects
				(font
					(size 1.27 1.27)
					(thickness 0.15)
				)
			)
		)
		(property "Author" "Antmicro"
			(at 0 0 0)
			(layer "B.Fab")
			(hide yes)
			(effects
				(font
					(size 1 1)
					(thickness 0.15)
				)
				(justify mirror)
			)
		)
		(property "License" "Apache-2.0"
			(at 0 0 0)
			(layer "B.Fab")
			(hide yes)
			(effects
				(font
					(size 1 1)
					(thickness 0.15)
				)
				(justify mirror)
			)
		)
		(property "MPN" "CR0402-FX-2200GLF"
			(at 0 0 0)
			(layer "B.Fab")
			(hide yes)
			(effects
				(font
					(size 1 1)
					(thickness 0.15)
				)
				(justify mirror)
			)
		)
		(property "Manufacturer" "Bourns"
			(at 0 0 0)
			(layer "B.Fab")
			(hide yes)
			(effects
				(font
					(size 1 1)
					(thickness 0.15)
				)
				(justify mirror)
			)
		)
		(property "Public" "False"
			(at 0 0 0)
			(layer "B.Fab")
			(hide yes)
			(effects
				(font
					(size 1 1)
					(thickness 0.15)
				)
				(justify mirror)
			)
		)
		(property "Tolerance" "1%"
			(at 0 0 0)
			(layer "B.Fab")
			(hide yes)
			(effects
				(font
					(size 1 1)
					(thickness 0.15)
				)
				(justify mirror)
			)
		)
		(property "Val" "220R"
			(at 0 0 0)
			(layer "B.Fab")
			(hide yes)
			(effects
				(font
					(size 1 1)
					(thickness 0.15)
				)
				(justify mirror)
			)
		)
		(sheetname "M.2 key M #1")
		(sheetfile "m2keym_low.kicad_sch")
		(attr smd)
		(fp_rect
			(start -0.925 0.47)
			(end 0.925 -0.47)
			(stroke
				(width 0.05)
				(type default)
			)
			(fill no)
			(layer "B.CrtYd")
		)
		(fp_rect
			(start -0.5 0.25)
			(end 0.5 -0.25)
			(stroke
				(width 0.15)
				(type solid)
			)
			(fill no)
			(layer "B.Fab")
		)
		(pad "1" smd roundrect
			(at -0.48 0)
			(size 0.59 0.64)
			(layers "B.Cu" "B.Mask" "B.Paste")
			(roundrect_rratio 0.25)
			(net 891 "Net-(D13-A)")
			(pintype "passive")
			(teardrops
				(best_length_ratio 0.2)
				(max_length 1)
				(best_width_ratio 0.9)
				(max_width 2)
				(curved_edges yes)
				(filter_ratio 0.9)
				(enabled yes)
				(allow_two_segments yes)
				(prefer_zone_connections yes)
			)
		)
		(pad "2" smd roundrect
			(at 0.48 0)
			(size 0.59 0.64)
			(layers "B.Cu" "B.Mask" "B.Paste")
			(roundrect_rratio 0.25)
			(net 2 "+3V3")
			(pintype "passive")
			(teardrops
				(best_length_ratio 0.2)
				(max_length 1)
				(best_width_ratio 0.9)
				(max_width 2)
				(curved_edges yes)
				(filter_ratio 0.9)
				(enabled yes)
				(allow_two_segments yes)
				(prefer_zone_connections yes)
			)
		)
	)
	(footprint "antmicro-footprints:R_0402_1005Metric"
		(layer "B.Cu")
		(at 148.86 133.87 180)
		(descr "Resistor SMD 0402")
		(tags "resistor SMD 0402")
		(property "Reference" "R267"
			(at 0.36 4.91 0)
			(layer "B.SilkS")
			(effects
				(font
					(size 0.7 0.7)
					(thickness 0.15)
				)
				(justify left bottom mirror)
			)
		)
		(property "Value" "R_10k_0402"
			(at -1.011843 -1.772047 0)
			(layer "B.Fab")
			(effects
				(font
					(size 0.7 0.7)
					(thickness 0.15)
				)
				(justify left bottom mirror)
			)
		)
		(property "Datasheet" "https://www.bourns.com/docs/product-datasheets/cr.pdf"
			(at 0 0 180)
			(layer "F.Fab")
			(hide yes)
			(effects
				(font
					(size 1.27 1.27)
					(thickness 0.15)
				)
			)
		)
		(property "Author" "Antmicro"
			(at 297.72 267.74 0)
			(layer "B.Fab")
			(hide yes)
			(effects
				(font
					(size 1 1)
					(thickness 0.15)
				)
				(justify mirror)
			)
		)
		(property "License" "Apache-2.0"
			(at 297.72 267.74 0)
			(layer "B.Fab")
			(hide yes)
			(effects
				(font
					(size 1 1)
					(thickness 0.15)
				)
				(justify mirror)
			)
		)
		(property "MPN" "CR0402-FX-1002GLF"
			(at 297.72 267.74 0)
			(layer "B.Fab")
			(hide yes)
			(effects
				(font
					(size 1 1)
					(thickness 0.15)
				)
				(justify mirror)
			)
		)
		(property "Manufacturer" "Bourns"
			(at 297.72 267.74 0)
			(layer "B.Fab")
			(hide yes)
			(effects
				(font
					(size 1 1)
					(thickness 0.15)
				)
				(justify mirror)
			)
		)
		(property "Public" "False"
			(at 297.72 267.74 0)
			(layer "B.Fab")
			(hide yes)
			(effects
				(font
					(size 1 1)
					(thickness 0.15)
				)
				(justify mirror)
			)
		)
		(property "Tolerance" "1%"
			(at 297.72 267.74 0)
			(layer "B.Fab")
			(hide yes)
			(effects
				(font
					(size 1 1)
					(thickness 0.15)
				)
				(justify mirror)
			)
		)
		(property "Val" "10k"
			(at 297.72 267.74 0)
			(layer "B.Fab")
			(hide yes)
			(effects
				(font
					(size 1 1)
					(thickness 0.15)
				)
				(justify mirror)
			)
		)
		(sheetname "KR to SFI #1")
		(sheetfile "kr_sfi.kicad_sch")
		(attr smd)
		(fp_rect
			(start -0.925 0.47)
			(end 0.925 -0.47)
			(stroke
				(width 0.05)
				(type default)
			)
			(fill no)
			(layer "B.CrtYd")
		)
		(fp_rect
			(start -0.5 0.25)
			(end 0.5 -0.25)
			(stroke
				(width 0.15)
				(type solid)
			)
			(fill no)
			(layer "B.Fab")
		)
		(pad "1" smd roundrect
			(at -0.48 0 180)
			(size 0.59 0.64)
			(layers "B.Cu" "B.Mask" "B.Paste")
			(roundrect_rratio 0.25)
			(net 660 "Net-(U43B-~{PDTRXB})")
			(pintype "passive")
			(teardrops
				(best_length_ratio 0.2)
				(max_length 1)
				(best_width_ratio 0.9)
				(max_width 2)
				(curved_edges yes)
				(filter_ratio 0.9)
				(enabled yes)
				(allow_two_segments yes)
				(prefer_zone_connections yes)
			)
		)
		(pad "2" smd roundrect
			(at 0.48 0 180)
			(size 0.59 0.64)
			(layers "B.Cu" "B.Mask" "B.Paste")
			(roundrect_rratio 0.25)
			(net 78 "+1V8")
			(pintype "passive")
			(teardrops
				(best_length_ratio 0.2)
				(max_length 1)
				(best_width_ratio 0.9)
				(max_width 2)
				(curved_edges yes)
				(filter_ratio 0.9)
				(enabled yes)
				(allow_two_segments yes)
				(prefer_zone_connections yes)
			)
		)
	)
)
